(kicad_pcb
	(version 20260206)
	(generator "pcbnew")
	(generator_version "10.0")
	(general
		(thickness 1.6)
		(legacy_teardrops no)
	)
	(paper "A4")
	(title_block
		(title "03242023_DA0F0TMBIJ0_F0T_Motherboard_J_brd_V01_OCP.brd")
		(comment 1 "Grand Teton / footprints 1260-1264 of 6105")
	)
	(layers
		(0 "F.Cu" signal "TOP")
		(4 "In1.Cu" signal "GND")
		(6 "In2.Cu" signal "IN1")
		(8 "In3.Cu" signal "GND1")
		(10 "In4.Cu" signal "IN2")
		(12 "In5.Cu" signal "GND2")
		(14 "In6.Cu" signal "IN3")
		(16 "In7.Cu" signal "GND3")
		(18 "In8.Cu" signal "VCC")
		(20 "In9.Cu" signal "VCC1")
		(22 "In10.Cu" signal "GND4")
		(24 "In11.Cu" signal "IN4")
		(26 "In12.Cu" signal "GND5")
		(28 "In13.Cu" signal "IN5")
		(30 "In14.Cu" signal "GND6")
		(32 "In15.Cu" signal "IN6")
		(34 "In16.Cu" signal "GND7")
		(2 "B.Cu" signal "BOTTOM")
		(9 "F.Adhes" user "F.Adhesive")
		(11 "B.Adhes" user "B.Adhesive")
		(13 "F.Paste" user "Package Geometry/Pastemask Top")
		(15 "B.Paste" user "Package Geometry/Pastemask Bottom")
		(5 "F.SilkS" user "Ref Des/Silkscreen Top")
		(7 "B.SilkS" user "Ref Des/Silkscreen Bottom")
		(1 "F.Mask" user "Board Geometry/Soldermask Top")
		(3 "B.Mask" user "Board Geometry/Soldermask Bottom")
		(17 "Dwgs.User" user "User.Drawings")
		(19 "Cmts.User" user "User.Comments")
		(21 "Eco1.User" user "User.Eco1")
		(23 "Eco2.User" user "User.Eco2")
		(25 "Edge.Cuts" user "Board Geometry/Outline")
		(27 "Margin" user)
		(31 "F.CrtYd" user "Package Geometry/Place Bound Top")
		(29 "B.CrtYd" user "Package Geometry/Place Bound Bottom")
		(35 "F.Fab" user "Ref Des/Assembly Top")
		(33 "B.Fab" user "Ref Des/Assembly Bottom")
	)
	(footprint ""
		(layer "F.Cu")
		(at 239.7125 -249.339608 -90)
		(property "Reference" "R4501"
			(at 0 0 270)
			(layer "F.SilkS")
			(hide yes)
			(effects
				(font
					(size 1.27 1.27)
				)
			)
		)
		(property "Value" ""
			(at 0 0 270)
			(layer "F.Fab")
			(effects
				(font
					(size 1.27 1.27)
				)
			)
		)
		(duplicate_pad_numbers_are_jumpers no)
		(fp_line
			(start -0.7874 0.4064)
			(end -0.7874 -0.4064)
			(stroke
				(width 0.1524)
				(type default)
			)
			(layer "F.SilkS")
		)
		(fp_line
			(start 0.7874 0.4064)
			(end -0.7874 0.4064)
			(stroke
				(width 0.1524)
				(type default)
			)
			(layer "F.SilkS")
		)
		(fp_line
			(start -0.7874 -0.4064)
			(end 0.7874 -0.4064)
			(stroke
				(width 0.1524)
				(type default)
			)
			(layer "F.SilkS")
		)
		(fp_line
			(start 0.7874 -0.4064)
			(end 0.7874 0.4064)
			(stroke
				(width 0.1524)
				(type default)
			)
			(layer "F.SilkS")
		)
		(fp_line
			(start -0.67945 0.3048)
			(end -0.67945 -0.305054)
			(stroke
				(width 0.1)
				(type default)
			)
			(layer "F.Fab")
		)
		(fp_line
			(start -0.12065 0.3048)
			(end -0.67945 0.3048)
			(stroke
				(width 0.1)
				(type default)
			)
			(layer "F.Fab")
		)
		(fp_line
			(start 0.120396 0.3048)
			(end 0.120396 0.2794)
			(stroke
				(width 0.1)
				(type default)
			)
			(layer "F.Fab")
		)
		(fp_line
			(start 0.67945 0.3048)
			(end 0.120396 0.3048)
			(stroke
				(width 0.1)
				(type default)
			)
			(layer "F.Fab")
		)
		(fp_line
			(start -0.12065 0.2794)
			(end -0.12065 0.3048)
			(stroke
				(width 0.1)
				(type default)
			)
			(layer "F.Fab")
		)
		(fp_line
			(start 0.120396 0.2794)
			(end -0.12065 0.2794)
			(stroke
				(width 0.1)
				(type default)
			)
			(layer "F.Fab")
		)
		(fp_line
			(start -0.12065 -0.2794)
			(end 0.12065 -0.2794)
			(stroke
				(width 0.1)
				(type default)
			)
			(layer "F.Fab")
		)
		(fp_line
			(start 0.12065 -0.2794)
			(end 0.12065 -0.3048)
			(stroke
				(width 0.1)
				(type default)
			)
			(layer "F.Fab")
		)
		(fp_line
			(start 0.12065 -0.3048)
			(end 0.67945 -0.3048)
			(stroke
				(width 0.1)
				(type default)
			)
			(layer "F.Fab")
		)
		(fp_line
			(start 0.67945 -0.3048)
			(end 0.67945 0.3048)
			(stroke
				(width 0.1)
				(type default)
			)
			(layer "F.Fab")
		)
		(fp_line
			(start -0.67945 -0.305054)
			(end -0.12065 -0.305054)
			(stroke
				(width 0.1)
				(type default)
			)
			(layer "F.Fab")
		)
		(fp_line
			(start -0.12065 -0.305054)
			(end -0.12065 -0.2794)
			(stroke
				(width 0.1)
				(type default)
			)
			(layer "F.Fab")
		)
		(pad "1" smd circle
			(at -0.40005 0 270)
			(size 0 0)
			(layers "F.Cu" "F.Mask" "F.Paste")
			(net "CLK_GEN2_XTAL_IN_R")
		)
		(pad "2" smd circle
			(at 0.40005 0 270)
			(size 0 0)
			(layers "F.Cu" "F.Mask" "F.Paste")
			(net "CLK_GEN2_XTAL_IN")
		)
	)
	(footprint ""
		(layer "F.Cu")
		(at 45.622972 -434.725318)
		(property "Reference" "U194"
			(at -2.747772 -2.051812 0)
			(unlocked yes)
			(layer "F.SilkS")
			(effects
				(font
					(size 0.7874 0.5842)
					(thickness 0.1524)
				)
				(justify left)
			)
		)
		(property "Value" ""
			(at 0 0 0)
			(layer "F.Fab")
			(effects
				(font
					(size 1.27 1.27)
				)
			)
		)
		(duplicate_pad_numbers_are_jumpers no)
		(fp_line
			(start -1.3716 -1.524)
			(end -0.508 -1.524)
			(stroke
				(width 0.1524)
				(type default)
			)
			(layer "F.SilkS")
		)
		(fp_line
			(start -1.3716 1.524)
			(end -1.3716 -1.524)
			(stroke
				(width 0.1524)
				(type default)
			)
			(layer "F.SilkS")
		)
		(fp_line
			(start -0.508 -1.524)
			(end 0 -1.016)
			(stroke
				(width 0.1524)
				(type default)
			)
			(layer "F.SilkS")
		)
		(fp_line
			(start 0 -1.016)
			(end 0.508 -1.524)
			(stroke
				(width 0.1524)
				(type default)
			)
			(layer "F.SilkS")
		)
		(fp_line
			(start 0.508 -1.524)
			(end 1.3716 -1.524)
			(stroke
				(width 0.1524)
				(type default)
			)
			(layer "F.SilkS")
		)
		(fp_line
			(start 1.3716 -1.524)
			(end 1.3716 1.524)
			(stroke
				(width 0.1524)
				(type default)
			)
			(layer "F.SilkS")
		)
		(fp_line
			(start 1.3716 1.524)
			(end -1.3716 1.524)
			(stroke
				(width 0.1524)
				(type default)
			)
			(layer "F.SilkS")
		)
		(fp_poly
			(pts
				(xy -3.6703 -1.331468) (xy -3.11658 -1.0033) (xy -3.6703 -0.706628)
			)
			(stroke
				(width 0)
				(type default)
			)
			(fill yes)
			(layer "F.SilkS")
		)
		(fp_line
			(start -2.54 -1.0668)
			(end -1.5494 -1.0668)
			(stroke
				(width 0.1)
				(type default)
			)
			(layer "F.Fab")
		)
		(fp_line
			(start -2.54 1.0668)
			(end -2.54 -1.0668)
			(stroke
				(width 0.1)
				(type default)
			)
			(layer "F.Fab")
		)
		(fp_line
			(start -1.5494 -1.524)
			(end 1.5494 -1.524)
			(stroke
				(width 0.1)
				(type default)
			)
			(layer "F.Fab")
		)
		(fp_line
			(start -1.5494 -1.0668)
			(end -1.5494 -1.524)
			(stroke
				(width 0.1)
				(type default)
			)
			(layer "F.Fab")
		)
		(fp_line
			(start -1.5494 1.0668)
			(end -2.54 1.0668)
			(stroke
				(width 0.1)
				(type default)
			)
			(layer "F.Fab")
		)
		(fp_line
			(start -1.5494 1.0668)
			(end -1.5494 -1.0668)
			(stroke
				(width 0.1)
				(type default)
			)
			(layer "F.Fab")
		)
		(fp_line
			(start -1.5494 1.524)
			(end -1.5494 1.0668)
			(stroke
				(width 0.1)
				(type default)
			)
			(layer "F.Fab")
		)
		(fp_line
			(start 1.5494 -1.524)
			(end 1.5494 -1.0668)
			(stroke
				(width 0.1)
				(type default)
			)
			(layer "F.Fab")
		)
		(fp_line
			(start 1.5494 -1.0668)
			(end 1.5494 1.0668)
			(stroke
				(width 0.1)
				(type default)
			)
			(layer "F.Fab")
		)
		(fp_line
			(start 1.5494 -1.0668)
			(end 2.54 -1.0668)
			(stroke
				(width 0.1)
				(type default)
			)
			(layer "F.Fab")
		)
		(fp_line
			(start 1.5494 1.0668)
			(end 1.5494 1.524)
			(stroke
				(width 0.1)
				(type default)
			)
			(layer "F.Fab")
		)
		(fp_line
			(start 1.5494 1.524)
			(end -1.5494 1.524)
			(stroke
				(width 0.1)
				(type default)
			)
			(layer "F.Fab")
		)
		(fp_line
			(start 2.54 -1.0668)
			(end 2.54 1.0668)
			(stroke
				(width 0.1)
				(type default)
			)
			(layer "F.Fab")
		)
		(fp_line
			(start 2.54 1.0668)
			(end 1.5494 1.0668)
			(stroke
				(width 0.1)
				(type default)
			)
			(layer "F.Fab")
		)
		(fp_poly
			(pts
				(xy -3.60172 -0.719328) (xy -3.60172 -1.344168) (xy -3.048 -1.016)
			)
			(stroke
				(width 0)
				(type default)
			)
			(fill yes)
			(layer "F.Fab")
		)
		(pad "1" smd rect
			(at -2.232406 -0.975106 270)
			(size 0.3556 1.4224)
			(layers "F.Cu" "F.Mask" "F.Paste")
			(net "SMB_BMC_GPU_EN_R1")
		)
		(pad "2" smd rect
			(at -2.232406 -0.32512 270)
			(size 0.3556 1.4224)
			(layers "F.Cu" "F.Mask" "F.Paste")
			(net "SMB_1_BMC_GPU_BUF_R_SCL")
		)
		(pad "3" smd rect
			(at -2.232406 0.32512 270)
			(size 0.3556 1.4224)
			(layers "F.Cu" "F.Mask" "F.Paste")
			(net "SMB_1_BMC_GPU_R_SCL")
		)
		(pad "4" smd rect
			(at -2.232406 0.975106 270)
			(size 0.3556 1.4224)
			(layers "F.Cu" "F.Mask" "F.Paste")
			(net "GND")
		)
		(pad "5" smd rect
			(at 2.232406 0.975106 270)
			(size 0.3556 1.4224)
			(layers "F.Cu" "F.Mask" "F.Paste")
			(net "Net_1936")
		)
		(pad "6" smd rect
			(at 2.232406 0.32512 270)
			(size 0.3556 1.4224)
			(layers "F.Cu" "F.Mask" "F.Paste")
			(net "SMB_1_BMC_GPU_R_SDA")
		)
		(pad "7" smd rect
			(at 2.232406 -0.32512 270)
			(size 0.3556 1.4224)
			(layers "F.Cu" "F.Mask" "F.Paste")
			(net "SMB_1_BMC_GPU_BUF_R_SDA")
		)
		(pad "8" smd rect
			(at 2.232406 -0.975106 270)
			(size 0.3556 1.4224)
			(layers "F.Cu" "F.Mask" "F.Paste")
			(net "P3V3_AUX")
		)
	)
	(footprint ""
		(layer "F.Cu")
		(at 15.436596 -392.199876 180)
		(property "Reference" "R3273"
			(at 0 0 180)
			(layer "F.SilkS")
			(hide yes)
			(effects
				(font
					(size 1.27 1.27)
				)
			)
		)
		(property "Value" ""
			(at 0 0 180)
			(layer "F.Fab")
			(effects
				(font
					(size 1.27 1.27)
				)
			)
		)
		(duplicate_pad_numbers_are_jumpers no)
		(fp_line
			(start 0.7874 0.4064)
			(end -0.7874 0.4064)
			(stroke
				(width 0.1524)
				(type default)
			)
			(layer "F.SilkS")
		)
		(fp_line
			(start 0.7874 -0.4064)
			(end 0.7874 0.4064)
			(stroke
				(width 0.1524)
				(type default)
			)
			(layer "F.SilkS")
		)
		(fp_line
			(start -0.7874 0.4064)
			(end -0.7874 -0.4064)
			(stroke
				(width 0.1524)
				(type default)
			)
			(layer "F.SilkS")
		)
		(fp_line
			(start -0.7874 -0.4064)
			(end 0.7874 -0.4064)
			(stroke
				(width 0.1524)
				(type default)
			)
			(layer "F.SilkS")
		)
		(fp_line
			(start 0.67945 0.3048)
			(end 0.120396 0.3048)
			(stroke
				(width 0.1)
				(type default)
			)
			(layer "F.Fab")
		)
		(fp_line
			(start 0.67945 -0.3048)
			(end 0.67945 0.3048)
			(stroke
				(width 0.1)
				(type default)
			)
			(layer "F.Fab")
		)
		(fp_line
			(start 0.12065 -0.2794)
			(end 0.12065 -0.3048)
			(stroke
				(width 0.1)
				(type default)
			)
			(layer "F.Fab")
		)
		(fp_line
			(start 0.12065 -0.3048)
			(end 0.67945 -0.3048)
			(stroke
				(width 0.1)
				(type default)
			)
			(layer "F.Fab")
		)
		(fp_line
			(start 0.120396 0.3048)
			(end 0.120396 0.2794)
			(stroke
				(width 0.1)
				(type default)
			)
			(layer "F.Fab")
		)
		(fp_line
			(start 0.120396 0.2794)
			(end -0.12065 0.2794)
			(stroke
				(width 0.1)
				(type default)
			)
			(layer "F.Fab")
		)
		(fp_line
			(start -0.12065 0.3048)
			(end -0.67945 0.3048)
			(stroke
				(width 0.1)
				(type default)
			)
			(layer "F.Fab")
		)
		(fp_line
			(start -0.12065 0.2794)
			(end -0.12065 0.3048)
			(stroke
				(width 0.1)
				(type default)
			)
			(layer "F.Fab")
		)
		(fp_line
			(start -0.12065 -0.2794)
			(end 0.12065 -0.2794)
			(stroke
				(width 0.1)
				(type default)
			)
			(layer "F.Fab")
		)
		(fp_line
			(start -0.12065 -0.305054)
			(end -0.12065 -0.2794)
			(stroke
				(width 0.1)
				(type default)
			)
			(layer "F.Fab")
		)
		(fp_line
			(start -0.67945 0.3048)
			(end -0.67945 -0.305054)
			(stroke
				(width 0.1)
				(type default)
			)
			(layer "F.Fab")
		)
		(fp_line
			(start -0.67945 -0.305054)
			(end -0.12065 -0.305054)
			(stroke
				(width 0.1)
				(type default)
			)
			(layer "F.Fab")
		)
		(pad "1" smd circle
			(at -0.40005 0 180)
			(size 0 0)
			(layers "F.Cu" "F.Mask" "F.Paste")
			(net "FM_P2E_FGA")
		)
		(pad "2" smd circle
			(at 0.40005 0 180)
			(size 0 0)
			(layers "F.Cu" "F.Mask" "F.Paste")
			(net "GND")
		)
	)
	(footprint ""
		(layer "F.Cu")
		(at 422.623742 -97.941892)
		(property "Reference" "PD103"
			(at -3.13182 2.806192 0)
			(unlocked yes)
			(layer "F.SilkS")
			(effects
				(font
					(size 0.7874 0.5842)
					(thickness 0.1524)
				)
				(justify left)
			)
		)
		(property "Value" ""
			(at 0 0 0)
			(layer "F.Fab")
			(effects
				(font
					(size 1.27 1.27)
				)
			)
		)
		(duplicate_pad_numbers_are_jumpers no)
		(fp_line
			(start -3.400044 -1.459992)
			(end 4.107942 -1.459992)
			(stroke
				(width 0.1524)
				(type default)
			)
			(layer "F.SilkS")
		)
		(fp_line
			(start -3.400044 1.459992)
			(end -3.400044 -1.459992)
			(stroke
				(width 0.1524)
				(type default)
			)
			(layer "F.SilkS")
		)
		(fp_line
			(start 4.107942 -1.459992)
			(end 4.107942 1.459992)
			(stroke
				(width 0.1524)
				(type default)
			)
			(layer "F.SilkS")
		)
		(fp_line
			(start 4.107942 1.459992)
			(end -3.400044 1.459992)
			(stroke
				(width 0.1524)
				(type default)
			)
			(layer "F.SilkS")
		)
		(fp_rect
			(start 3.308096 1.459992)
			(end 4.107942 -1.459992)
			(stroke
				(width 0)
				(type default)
			)
			(fill yes)
			(layer "F.SilkS")
		)
		(fp_line
			(start -2.29997 -1.459992)
			(end 2.29997 -1.459992)
			(stroke
				(width 0.1)
				(type default)
			)
			(layer "F.Fab")
		)
		(fp_line
			(start -2.29997 1.459992)
			(end -2.29997 -1.459992)
			(stroke
				(width 0.1)
				(type default)
			)
			(layer "F.Fab")
		)
		(fp_line
			(start 2.29997 -1.459992)
			(end 2.29997 1.459992)
			(stroke
				(width 0.1)
				(type default)
			)
			(layer "F.Fab")
		)
		(fp_line
			(start 2.29997 1.459992)
			(end -2.29997 1.459992)
			(stroke
				(width 0.1)
				(type default)
			)
			(layer "F.Fab")
		)
		(fp_text user "+"
			(at -4.7752 -0.12065 0)
			(unlocked yes)
			(layer "F.SilkS")
			(effects
				(font
					(size 1.905 1.4224)
					(thickness 0.1524)
				)
				(justify left)
			)
		)
		(fp_text user "-"
			(at 3.8735 2.64795 180)
			(unlocked yes)
			(layer "F.SilkS")
			(effects
				(font
					(size 1.905 1.4224)
					(thickness 0.1524)
				)
				(justify left)
			)
		)
		(fp_text user "+"
			(at -4.7752 -0.12065 0)
			(unlocked yes)
			(layer "F.Fab")
			(effects
				(font
					(size 1.905 1.4224)
					(thickness 0.1524)
				)
				(justify left)
			)
		)
		(fp_text user "-"
			(at 5.4102 0.29845 180)
			(unlocked yes)
			(layer "F.Fab")
			(effects
				(font
					(size 1.905 1.4224)
					(thickness 0.1524)
				)
				(justify left)
			)
		)
		(pad "A" smd rect
			(at -1.999996 0 90)
			(size 1.7018 2.5146)
			(layers "F.Cu" "F.Mask" "F.Paste")
			(net "GND")
		)
		(pad "C" smd rect
			(at 1.999996 0 90)
			(size 1.7018 2.5146)
			(layers "F.Cu" "F.Mask" "F.Paste")
			(net "P3V3_OCP_SFF_R")
		)
	)
	(footprint ""
		(layer "F.Cu")
		(at 77.966824 -142.587218 90)
		(property "Reference" "R666"
			(at 0 0 90)
			(layer "F.SilkS")
			(hide yes)
			(effects
				(font
					(size 1.27 1.27)
				)
			)
		)
		(property "Value" ""
			(at 0 0 90)
			(layer "F.Fab")
			(effects
				(font
					(size 1.27 1.27)
				)
			)
		)
		(duplicate_pad_numbers_are_jumpers no)
		(fp_line
			(start 0.7874 -0.4064)
			(end 0.7874 0.4064)
			(stroke
				(width 0.1524)
				(type default)
			)
			(layer "F.SilkS")
		)
		(fp_line
			(start -0.7874 -0.4064)
			(end 0.7874 -0.4064)
			(stroke
				(width 0.1524)
				(type default)
			)
			(layer "F.SilkS")
		)
		(fp_line
			(start 0.7874 0.4064)
			(end -0.7874 0.4064)
			(stroke
				(width 0.1524)
				(type default)
			)
			(layer "F.SilkS")
		)
		(fp_line
			(start -0.7874 0.4064)
			(end -0.7874 -0.4064)
			(stroke
				(width 0.1524)
				(type default)
			)
			(layer "F.SilkS")
		)
		(fp_line
			(start -0.12065 -0.305054)
			(end -0.12065 -0.2794)
			(stroke
				(width 0.1)
				(type default)
			)
			(layer "F.Fab")
		)
		(fp_line
			(start -0.67945 -0.305054)
			(end -0.12065 -0.305054)
			(stroke
				(width 0.1)
				(type default)
			)
			(layer "F.Fab")
		)
		(fp_line
			(start 0.67945 -0.3048)
			(end 0.67945 0.3048)
			(stroke
				(width 0.1)
				(type default)
			)
			(layer "F.Fab")
		)
		(fp_line
			(start 0.12065 -0.3048)
			(end 0.67945 -0.3048)
			(stroke
				(width 0.1)
				(type default)
			)
			(layer "F.Fab")
		)
		(fp_line
			(start 0.12065 -0.2794)
			(end 0.12065 -0.3048)
			(stroke
				(width 0.1)
				(type default)
			)
			(layer "F.Fab")
		)
		(fp_line
			(start -0.12065 -0.2794)
			(end 0.12065 -0.2794)
			(stroke
				(width 0.1)
				(type default)
			)
			(layer "F.Fab")
		)
		(fp_line
			(start 0.120396 0.2794)
			(end -0.12065 0.2794)
			(stroke
				(width 0.1)
				(type default)
			)
			(layer "F.Fab")
		)
		(fp_line
			(start -0.12065 0.2794)
			(end -0.12065 0.3048)
			(stroke
				(width 0.1)
				(type default)
			)
			(layer "F.Fab")
		)
		(fp_line
			(start 0.67945 0.3048)
			(end 0.120396 0.3048)
			(stroke
				(width 0.1)
				(type default)
			)
			(layer "F.Fab")
		)
		(fp_line
			(start 0.120396 0.3048)
			(end 0.120396 0.2794)
			(stroke
				(width 0.1)
				(type default)
			)
			(layer "F.Fab")
		)
		(fp_line
			(start -0.12065 0.3048)
			(end -0.67945 0.3048)
			(stroke
				(width 0.1)
				(type default)
			)
			(layer "F.Fab")
		)
		(fp_line
			(start -0.67945 0.3048)
			(end -0.67945 -0.305054)
			(stroke
				(width 0.1)
				(type default)
			)
			(layer "F.Fab")
		)
		(pad "1" smd circle
			(at -0.40005 0 90)
			(size 0 0)
			(layers "F.Cu" "F.Mask" "F.Paste")
			(net "I3C_SPD_DDRABCD_CPU1_R_SDA")
		)
		(pad "2" smd circle
			(at 0.40005 0 90)
			(size 0 0)
			(layers "F.Cu" "F.Mask" "F.Paste")
			(net "I3C_SPD_DDRABCD_CPU1_LVC1_R_SDA")
		)
	)
)
